(kicad_pcb
	(version 20241229)
	(generator "pcbnew")
	(generator_version "9.0")
	(general
		(thickness 1.63)
		(legacy_teardrops no)
	)
	(paper "A4")
	(title_block
		(title "CM4 Baseboard")
		(date "2026-01-05")
		(rev "1.1.1")
		(company "Antmicro Ltd")
		(comment 1 "www.antmicro.com")
		(comment 9 "footprints 487-491 of 506")
	)
	(layers
		(0 "F.Cu" signal)
		(4 "In1.Cu" power)
		(6 "In2.Cu" power)
		(8 "In3.Cu" signal)
		(10 "In4.Cu" signal)
		(2 "B.Cu" signal)
		(9 "F.Adhes" user "F.Adhesive")
		(11 "B.Adhes" user "B.Adhesive")
		(13 "F.Paste" user)
		(15 "B.Paste" user)
		(5 "F.SilkS" user "F.Silkscreen")
		(7 "B.SilkS" user "B.Silkscreen")
		(1 "F.Mask" user)
		(3 "B.Mask" user)
		(17 "Dwgs.User" user "User.Drawings")
		(19 "Cmts.User" user "User.Comments")
		(21 "Eco1.User" user "User.Eco1")
		(23 "Eco2.User" user "User.Eco2")
		(25 "Edge.Cuts" user)
		(27 "Margin" user)
		(31 "F.CrtYd" user "F.Courtyard")
		(29 "B.CrtYd" user "B.Courtyard")
		(35 "F.Fab" user)
		(33 "B.Fab" user)
	)
	(footprint "antmicro-footprints:DFN3538"
		(layer "B.Cu")
		(at 63.917962 121.5665 180)
		(property "Reference" "D402"
			(at -1.412038 2.6765 0)
			(unlocked yes)
			(layer "B.SilkS")
			(effects
				(font
					(size 0.7 0.7)
					(thickness 0.15)
				)
				(justify left bottom mirror)
			)
		)
		(property "Value" "CD-MMBL110S"
			(at 0 -3.5 0)
			(unlocked yes)
			(layer "B.Fab")
			(effects
				(font
					(size 0.7 0.7)
					(thickness 0.15)
				)
				(justify left bottom mirror)
			)
		)
		(property "Datasheet" "https://www.bourns.com/docs/product-datasheets/CD-MMBL110S.pdf"
			(at 0 0 180)
			(layer "B.Fab")
			(hide yes)
			(effects
				(font
					(size 1.27 1.27)
					(thickness 0.15)
				)
			)
		)
		(property "MPN" "CD-MMBL110S"
			(at 0 0 180)
			(unlocked yes)
			(layer "B.Fab")
			(hide yes)
			(effects
				(font
					(size 1 1)
					(thickness 0.15)
				)
				(justify mirror)
			)
		)
		(property "Manufacturer" "Bourns"
			(at 0 0 180)
			(unlocked yes)
			(layer "B.Fab")
			(hide yes)
			(effects
				(font
					(size 1 1)
					(thickness 0.15)
				)
				(justify mirror)
			)
		)
		(property "Author" "Antmicro"
			(at 0 0 180)
			(unlocked yes)
			(layer "B.Fab")
			(hide yes)
			(effects
				(font
					(size 1 1)
					(thickness 0.15)
				)
				(justify mirror)
			)
		)
		(property "License" "Apache-2.0"
			(at 0 0 180)
			(unlocked yes)
			(layer "B.Fab")
			(hide yes)
			(effects
				(font
					(size 1 1)
					(thickness 0.15)
				)
				(justify mirror)
			)
		)
		(sheetname "/Ethernet/")
		(sheetfile "ethernet.kicad_sch")
		(attr smd)
		(fp_line
			(start 1.8 2)
			(end 1.8 -2.05)
			(stroke
				(width 0.15)
				(type solid)
			)
			(layer "B.SilkS")
		)
		(fp_line
			(start 1.6 2)
			(end 1.8 2)
			(stroke
				(width 0.15)
				(type solid)
			)
			(layer "B.SilkS")
		)
		(fp_line
			(start 1.6 -2.05)
			(end 1.8 -2.05)
			(stroke
				(width 0.15)
				(type solid)
			)
			(layer "B.SilkS")
		)
		(fp_line
			(start 0.9 2.301)
			(end 0.598 2.301)
			(stroke
				(width 0.15)
				(type solid)
			)
			(layer "B.SilkS")
		)
		(fp_line
			(start 0.748 2.452)
			(end 0.748 2.15)
			(stroke
				(width 0.15)
				(type solid)
			)
			(layer "B.SilkS")
		)
		(fp_line
			(start -0.902 2.25)
			(end -0.6 2.25)
			(stroke
				(width 0.15)
				(type solid)
			)
			(layer "B.SilkS")
		)
		(fp_line
			(start -0.95 2)
			(end 0.95 2)
			(stroke
				(width 0.15)
				(type solid)
			)
			(layer "B.SilkS")
		)
		(fp_line
			(start -0.95 -2.05)
			(end 0.95 -2.05)
			(stroke
				(width 0.15)
				(type solid)
			)
			(layer "B.SilkS")
		)
		(fp_line
			(start -1.8 1.5)
			(end -1.8 -2.05)
			(stroke
				(width 0.15)
				(type solid)
			)
			(layer "B.SilkS")
		)
		(fp_line
			(start -1.8 -2.05)
			(end -1.6 -2.05)
			(stroke
				(width 0.15)
				(type solid)
			)
			(layer "B.SilkS")
		)
		(fp_rect
			(start -2.1 2.6)
			(end 2.1 -2.6)
			(stroke
				(width 0.05)
				(type solid)
			)
			(fill no)
			(layer "B.CrtYd")
		)
		(fp_line
			(start -1.051 2)
			(end -1.801 1.25)
			(stroke
				(width 0.15)
				(type solid)
			)
			(layer "B.Fab")
		)
		(fp_rect
			(start 1.8 -2.048)
			(end -1.8 2)
			(stroke
				(width 0.15)
				(type solid)
			)
			(fill no)
			(layer "B.Fab")
		)
		(fp_text user "~"
			(at -0.31 -2.7 0)
			(unlocked yes)
			(layer "B.SilkS")
			(effects
				(font
					(size 0.7 0.7)
					(thickness 0.15)
				)
				(justify left bottom mirror)
			)
		)
		(fp_text user "License: Apache-2.0"
			(at -2.1 -6.599 0)
			(layer "B.Fab")
			(effects
				(font
					(size 0.7 0.7)
					(thickness 0.15)
				)
				(justify left bottom mirror)
			)
		)
		(fp_text user "Author: Antmicro"
			(at -2.1 -5.599 0)
			(layer "B.Fab")
			(effects
				(font
					(size 0.7 0.7)
					(thickness 0.15)
				)
				(justify left bottom mirror)
			)
		)
		(fp_text user "${REFERENCE}"
			(at -2.1 -4.599 0)
			(layer "B.Fab")
			(effects
				(font
					(size 0.7 0.7)
					(thickness 0.15)
				)
				(justify left bottom mirror)
			)
		)
		(pad "1" smd roundrect
			(at -1.27 1.85 90)
			(size 1.4 0.48)
			(layers "B.Cu" "B.Mask" "B.Paste")
			(roundrect_rratio 0.25)
			(net 116 "Net-(D401-Pad1)")
			(pinfunction "1")
			(pintype "passive")
		)
		(pad "2" smd roundrect
			(at 1.27 1.85 90)
			(size 1.4 0.48)
			(layers "B.Cu" "B.Mask" "B.Paste")
			(roundrect_rratio 0.25)
			(net 117 "Net-(D401-Pad2)")
			(pinfunction "2")
			(pintype "passive")
		)
		(pad "3" smd roundrect
			(at -1.27 -1.85 90)
			(size 1.4 0.48)
			(layers "B.Cu" "B.Mask" "B.Paste")
			(roundrect_rratio 0.25)
			(net 63 "/Ethernet/PAIR_910")
			(pinfunction "3")
			(pintype "passive")
		)
		(pad "4" smd roundrect
			(at 1.27 -1.85 90)
			(size 1.4 0.48)
			(layers "B.Cu" "B.Mask" "B.Paste")
			(roundrect_rratio 0.25)
			(net 64 "/Ethernet/PAIR_78")
			(pinfunction "4")
			(pintype "passive")
		)
	)
	(footprint "antmicro-footprints:C_0402_1005Metric"
		(layer "B.Cu")
		(at 118.192962 129.7665 -90)
		(descr "Capacitor SMD 0402")
		(tags "capacitor SMD 0402")
		(property "Reference" "C503"
			(at -1.41 0.575 90)
			(layer "B.SilkS")
			(effects
				(font
					(size 0.7 0.7)
					(thickness 0.15)
				)
				(justify left bottom mirror)
			)
		)
		(property "Value" "C_10u_0402"
			(at -1.022927 -2.155213 90)
			(layer "B.Fab")
			(effects
				(font
					(size 0.7 0.7)
					(thickness 0.15)
				)
				(justify left bottom mirror)
			)
		)
		(property "Datasheet" "https://www.yageo.com/en/Chart/Download/pdf/CC0402MRX5R5BB106"
			(at 0 0 270)
			(layer "B.Fab")
			(hide yes)
			(effects
				(font
					(size 1.27 1.27)
					(thickness 0.15)
				)
			)
		)
		(property "MPN" "CC0402MRX5R5BB106"
			(at 0 0 270)
			(unlocked yes)
			(layer "B.Fab")
			(hide yes)
			(effects
				(font
					(size 1 1)
					(thickness 0.15)
				)
				(justify mirror)
			)
		)
		(property "Manufacturer" "YAGEO"
			(at 0 0 270)
			(unlocked yes)
			(layer "B.Fab")
			(hide yes)
			(effects
				(font
					(size 1 1)
					(thickness 0.15)
				)
				(justify mirror)
			)
		)
		(property "License" "Apache-2.0"
			(at 0 0 270)
			(unlocked yes)
			(layer "B.Fab")
			(hide yes)
			(effects
				(font
					(size 1 1)
					(thickness 0.15)
				)
				(justify mirror)
			)
		)
		(property "Author" "Antmicro"
			(at 0 0 270)
			(unlocked yes)
			(layer "B.Fab")
			(hide yes)
			(effects
				(font
					(size 1 1)
					(thickness 0.15)
				)
				(justify mirror)
			)
		)
		(property "Val" "10u"
			(at 0 0 270)
			(unlocked yes)
			(layer "B.Fab")
			(hide yes)
			(effects
				(font
					(size 1 1)
					(thickness 0.15)
				)
				(justify mirror)
			)
		)
		(property "Voltage" ""
			(at 0 0 270)
			(unlocked yes)
			(layer "B.Fab")
			(hide yes)
			(effects
				(font
					(size 1 1)
					(thickness 0.15)
				)
				(justify mirror)
			)
		)
		(property "Dielectric" ""
			(at 0 0 270)
			(unlocked yes)
			(layer "B.Fab")
			(hide yes)
			(effects
				(font
					(size 1 1)
					(thickness 0.15)
				)
				(justify mirror)
			)
		)
		(sheetname "/NVMe & microSD/")
		(sheetfile "nvme-micro-sd.kicad_sch")
		(attr smd)
		(fp_rect
			(start -0.925 0.47)
			(end 0.925 -0.47)
			(stroke
				(width 0.05)
				(type default)
			)
			(fill no)
			(layer "B.CrtYd")
		)
		(fp_line
			(start -0.494 0.25)
			(end 0.504 0.25)
			(stroke
				(width 0.15)
				(type solid)
			)
			(layer "B.Fab")
		)
		(fp_line
			(start 0.504 0.25)
			(end 0.504 -0.248)
			(stroke
				(width 0.15)
				(type solid)
			)
			(layer "B.Fab")
		)
		(fp_line
			(start -0.494 -0.248)
			(end -0.494 0.25)
			(stroke
				(width 0.15)
				(type solid)
			)
			(layer "B.Fab")
		)
		(fp_line
			(start 0.504 -0.248)
			(end -0.494 -0.248)
			(stroke
				(width 0.15)
				(type solid)
			)
			(layer "B.Fab")
		)
		(fp_text user "Author: Antmicro"
			(at -0.939 -3.399 90)
			(layer "B.Fab")
			(effects
				(font
					(size 0.7 0.7)
					(thickness 0.15)
				)
				(justify left bottom mirror)
			)
		)
		(fp_text user "${REFERENCE}"
			(at -0.939 -4.599 90)
			(layer "B.Fab")
			(effects
				(font
					(size 0.7 0.7)
					(thickness 0.15)
				)
				(justify left bottom mirror)
			)
		)
		(fp_text user "License: Apache-2.0"
			(at -0.939 -5.799 90)
			(layer "B.Fab")
			(effects
				(font
					(size 0.7 0.7)
					(thickness 0.15)
				)
				(justify left bottom mirror)
			)
		)
		(pad "1" smd roundrect
			(at -0.48 0 270)
			(size 0.59 0.64)
			(layers "B.Cu" "B.Mask" "B.Paste")
			(roundrect_rratio 0.25)
			(net 3 "GND")
			(pintype "passive")
		)
		(pad "2" smd roundrect
			(at 0.48 0 270)
			(size 0.59 0.64)
			(layers "B.Cu" "B.Mask" "B.Paste")
			(roundrect_rratio 0.25)
			(net 65 "3V3_SSD")
			(pintype "passive")
		)
	)
	(footprint "antmicro-footprints:R_0402_1005Metric"
		(layer "B.Cu")
		(at 65.692962 161.2165)
		(descr "Resistor SMD 0402")
		(tags "resistor SMD 0402")
		(property "Reference" "R320"
			(at 14.275 0.71 0)
			(layer "B.SilkS")
			(effects
				(font
					(size 0.7 0.7)
					(thickness 0.15)
				)
				(justify right bottom mirror)
			)
		)
		(property "Value" "R_6k8_0402"
			(at -1.011843 -1.772047 0)
			(layer "B.Fab")
			(effects
				(font
					(size 0.7 0.7)
					(thickness 0.15)
				)
				(justify right bottom mirror)
			)
		)
		(property "Datasheet" "https://www.bourns.com/docs/product-datasheets/cr.pdf"
			(at 0 0 0)
			(layer "B.Fab")
			(hide yes)
			(effects
				(font
					(size 1.27 1.27)
					(thickness 0.15)
				)
			)
		)
		(property "MPN" "CR0402-FX-6801GLF"
			(at 0 0 0)
			(unlocked yes)
			(layer "B.Fab")
			(hide yes)
			(effects
				(font
					(size 1 1)
					(thickness 0.15)
				)
				(justify mirror)
			)
		)
		(property "Manufacturer" "Bourns"
			(at 0 0 0)
			(unlocked yes)
			(layer "B.Fab")
			(hide yes)
			(effects
				(font
					(size 1 1)
					(thickness 0.15)
				)
				(justify mirror)
			)
		)
		(property "License" "Apache-2.0"
			(at 0 0 0)
			(unlocked yes)
			(layer "B.Fab")
			(hide yes)
			(effects
				(font
					(size 1 1)
					(thickness 0.15)
				)
				(justify mirror)
			)
		)
		(property "Author" "Antmicro"
			(at 0 0 0)
			(unlocked yes)
			(layer "B.Fab")
			(hide yes)
			(effects
				(font
					(size 1 1)
					(thickness 0.15)
				)
				(justify mirror)
			)
		)
		(property "Val" "6k8"
			(at 0 0 0)
			(unlocked yes)
			(layer "B.Fab")
			(hide yes)
			(effects
				(font
					(size 1 1)
					(thickness 0.15)
				)
				(justify mirror)
			)
		)
		(property "Tolerance" "1%"
			(at 0 0 0)
			(unlocked yes)
			(layer "B.Fab")
			(hide yes)
			(effects
				(font
					(size 1 1)
					(thickness 0.15)
				)
				(justify mirror)
			)
		)
		(sheetname "/Supply/")
		(sheetfile "supply.kicad_sch")
		(attr smd)
		(fp_rect
			(start -0.925 0.47)
			(end 0.925 -0.47)
			(stroke
				(width 0.05)
				(type default)
			)
			(fill no)
			(layer "B.CrtYd")
		)
		(fp_rect
			(start -0.5 0.25)
			(end 0.5 -0.25)
			(stroke
				(width 0.15)
				(type solid)
			)
			(fill no)
			(layer "B.Fab")
		)
		(fp_text user "License: Apache-2.0"
			(at -0.95 -5.169 180)
			(layer "B.Fab")
			(effects
				(font
					(size 0.7 0.7)
					(thickness 0.15)
				)
				(justify left bottom mirror)
			)
		)
		(fp_text user "Author: Antmicro"
			(at -0.95 -4.169 180)
			(layer "B.Fab")
			(effects
				(font
					(size 0.7 0.7)
					(thickness 0.15)
				)
				(justify left bottom mirror)
			)
		)
		(fp_text user "${REFERENCE}"
			(at -0.95 -3.168 180)
			(layer "B.Fab")
			(effects
				(font
					(size 0.7 0.7)
					(thickness 0.15)
				)
				(justify left bottom mirror)
			)
		)
		(pad "1" smd roundrect
			(at -0.48 0)
			(size 0.59 0.64)
			(layers "B.Cu" "B.Mask" "B.Paste")
			(roundrect_rratio 0.25)
			(net 355 "/Supply/FB_3V3")
			(pintype "passive")
		)
		(pad "2" smd roundrect
			(at 0.48 0)
			(size 0.59 0.64)
			(layers "B.Cu" "B.Mask" "B.Paste")
			(roundrect_rratio 0.25)
			(net 89 "/Supply/OUT_3V3")
			(pintype "passive")
		)
	)
	(footprint "antmicro-footprints:R_0402_1005Metric"
		(layer "B.Cu")
		(at 75.342962 135.0565)
		(descr "Resistor SMD 0402")
		(tags "resistor SMD 0402")
		(property "Reference" "R916"
			(at -3.815 0.34 0)
			(layer "B.SilkS")
			(effects
				(font
					(size 0.7 0.7)
					(thickness 0.15)
				)
				(justify right bottom mirror)
			)
		)
		(property "Value" "R_100k_0402"
			(at -1.011843 -1.772047 0)
			(layer "B.Fab")
			(effects
				(font
					(size 0.7 0.7)
					(thickness 0.15)
				)
				(justify right bottom mirror)
			)
		)
		(property "Datasheet" "https://www.bourns.com/docs/product-datasheets/cr.pdf"
			(at 0 0 0)
			(layer "B.Fab")
			(hide yes)
			(effects
				(font
					(size 1.27 1.27)
					(thickness 0.15)
				)
			)
		)
		(property "Manufacturer" "Bourns"
			(at 0 0 0)
			(unlocked yes)
			(layer "B.Fab")
			(hide yes)
			(effects
				(font
					(size 1 1)
					(thickness 0.15)
				)
				(justify mirror)
			)
		)
		(property "MPN" "CR0402-FX-1003GLF"
			(at 0 0 0)
			(unlocked yes)
			(layer "B.Fab")
			(hide yes)
			(effects
				(font
					(size 1 1)
					(thickness 0.15)
				)
				(justify mirror)
			)
		)
		(property "Val" "100k"
			(at 0 0 0)
			(unlocked yes)
			(layer "B.Fab")
			(hide yes)
			(effects
				(font
					(size 1 1)
					(thickness 0.15)
				)
				(justify mirror)
			)
		)
		(property "License" "Apache-2.0"
			(at 0 0 0)
			(unlocked yes)
			(layer "B.Fab")
			(hide yes)
			(effects
				(font
					(size 1 1)
					(thickness 0.15)
				)
				(justify mirror)
			)
		)
		(property "Author" "Antmicro"
			(at 0 0 0)
			(unlocked yes)
			(layer "B.Fab")
			(hide yes)
			(effects
				(font
					(size 1 1)
					(thickness 0.15)
				)
				(justify mirror)
			)
		)
		(property "Tolerance" "1%"
			(at 0 0 0)
			(unlocked yes)
			(layer "B.Fab")
			(hide yes)
			(effects
				(font
					(size 1 1)
					(thickness 0.15)
				)
				(justify mirror)
			)
		)
		(sheetname "/USB/")
		(sheetfile "usb.kicad_sch")
		(attr smd)
		(fp_rect
			(start -0.925 0.47)
			(end 0.925 -0.47)
			(stroke
				(width 0.05)
				(type default)
			)
			(fill no)
			(layer "B.CrtYd")
		)
		(fp_rect
			(start -0.5 0.25)
			(end 0.5 -0.25)
			(stroke
				(width 0.15)
				(type solid)
			)
			(fill no)
			(layer "B.Fab")
		)
		(fp_text user "License: Apache-2.0"
			(at -0.95 -5.169 180)
			(layer "B.Fab")
			(effects
				(font
					(size 0.7 0.7)
					(thickness 0.15)
				)
				(justify left bottom mirror)
			)
		)
		(fp_text user "${REFERENCE}"
			(at -0.95 -3.168 180)
			(layer "B.Fab")
			(effects
				(font
					(size 0.7 0.7)
					(thickness 0.15)
				)
				(justify left bottom mirror)
			)
		)
		(fp_text user "Author: Antmicro"
			(at -0.95 -4.169 180)
			(layer "B.Fab")
			(effects
				(font
					(size 0.7 0.7)
					(thickness 0.15)
				)
				(justify left bottom mirror)
			)
		)
		(pad "1" smd roundrect
			(at -0.48 0)
			(size 0.59 0.64)
			(layers "B.Cu" "B.Mask" "B.Paste")
			(roundrect_rratio 0.25)
			(net 26 "/USB/USBD_VBUS")
			(pintype "passive")
		)
		(pad "2" smd roundrect
			(at 0.48 0)
			(size 0.59 0.64)
			(layers "B.Cu" "B.Mask" "B.Paste")
			(roundrect_rratio 0.25)
			(net 29 "/USB/USBD_SVBUS")
			(pintype "passive")
		)
	)
	(footprint "antmicro-footprints:C_0805_2012Metric"
		(layer "B.Cu")
		(at 112.442962 137.5965 180)
		(descr "Capacitor SMD 0805")
		(tags "capacitor SMD 0805")
		(property "Reference" "C316"
			(at -1.355 -1.87 0)
			(layer "B.SilkS")
			(effects
				(font
					(size 0.7 0.7)
					(thickness 0.15)
				)
				(justify left bottom mirror)
			)
		)
		(property "Value" "C_22u_25V_0805"
			(at -2.055717 -1.963152 0)
			(layer "B.Fab")
			(effects
				(font
					(size 0.7 0.7)
					(thickness 0.15)
				)
				(justify left bottom mirror)
			)
		)
		(property "Datasheet" "https://product.samsungsem.com/mlcc/CL21A226MAYNNN.do"
			(at 0 0 180)
			(layer "B.Fab")
			(hide yes)
			(effects
				(font
					(size 1.27 1.27)
					(thickness 0.15)
				)
			)
		)
		(property "Manufacturer" "Samsung Electro-Mechanics"
			(at 0 0 180)
			(unlocked yes)
			(layer "B.Fab")
			(hide yes)
			(effects
				(font
					(size 1 1)
					(thickness 0.15)
				)
				(justify mirror)
			)
		)
		(property "MPN" "CL21A226MAYNNNE"
			(at 0 0 180)
			(unlocked yes)
			(layer "B.Fab")
			(hide yes)
			(effects
				(font
					(size 1 1)
					(thickness 0.15)
				)
				(justify mirror)
			)
		)
		(property "Val" "22u"
			(at 0 0 180)
			(unlocked yes)
			(layer "B.Fab")
			(hide yes)
			(effects
				(font
					(size 1 1)
					(thickness 0.15)
				)
				(justify mirror)
			)
		)
		(property "License" "Apache-2.0"
			(at 0 0 180)
			(unlocked yes)
			(layer "B.Fab")
			(hide yes)
			(effects
				(font
					(size 1 1)
					(thickness 0.15)
				)
				(justify mirror)
			)
		)
		(property "Author" "Antmicro"
			(at 0 0 180)
			(unlocked yes)
			(layer "B.Fab")
			(hide yes)
			(effects
				(font
					(size 1 1)
					(thickness 0.15)
				)
				(justify mirror)
			)
		)
		(property "Voltage" "25V"
			(at 0 0 180)
			(unlocked yes)
			(layer "B.Fab")
			(hide yes)
			(effects
				(font
					(size 1 1)
					(thickness 0.15)
				)
				(justify mirror)
			)
		)
		(property "Dielectric" "X5R"
			(at 0 0 180)
			(unlocked yes)
			(layer "B.Fab")
			(hide yes)
			(effects
				(font
					(size 1 1)
					(thickness 0.15)
				)
				(justify mirror)
			)
		)
		(property "Public" "False"
			(at 0 0 180)
			(unlocked yes)
			(layer "B.Fab")
			(hide yes)
			(effects
				(font
					(size 1 1)
					(thickness 0.15)
				)
				(justify mirror)
			)
		)
		(sheetname "/Supply/")
		(sheetfile "supply.kicad_sch")
		(attr smd)
		(fp_line
			(start -0.3 0.7)
			(end 0.3 0.7)
			(stroke
				(width 0.15)
				(type solid)
			)
			(layer "B.SilkS")
		)
		(fp_line
			(start -0.3 -0.7)
			(end 0.3 -0.7)
			(stroke
				(width 0.15)
				(type solid)
			)
			(layer "B.SilkS")
		)
		(fp_rect
			(start 1.95 0.9)
			(end -1.95 -0.9)
			(stroke
				(width 0.05)
				(type default)
			)
			(fill no)
			(layer "B.CrtYd")
		)
		(fp_rect
			(start -0.95 0.675)
			(end 0.95 -0.675)
			(stroke
				(width 0.15)
				(type solid)
			)
			(fill no)
			(layer "B.Fab")
		)
		(fp_text user "${REFERENCE}"
			(at -1.9 -3.947 0)
			(layer "B.Fab")
			(effects
				(font
					(size 0.7 0.7)
					(thickness 0.15)
				)
				(justify left bottom mirror)
			)
		)
		(fp_text user "License: Apache-2.0"
			(at -1.9 -4.947 0)
			(layer "B.Fab")
			(effects
				(font
					(size 0.7 0.7)
					(thickness 0.15)
				)
				(justify left bottom mirror)
			)
		)
		(fp_text user "Author: Antmicro"
			(at -1.9 -5.947 0)
			(layer "B.Fab")
			(effects
				(font
					(size 0.7 0.7)
					(thickness 0.15)
				)
				(justify left bottom mirror)
			)
		)
		(pad "1" smd roundrect
			(at -1.1 0 180)
			(size 1.2 1.3)
			(layers "B.Cu" "B.Mask" "B.Paste")
			(roundrect_rratio 0.25)
			(net 78 "/Supply/OUT_M2")
			(pintype "passive")
		)
		(pad "2" smd roundrect
			(at 1.1 0 180)
			(size 1.2 1.3)
			(layers "B.Cu" "B.Mask" "B.Paste")
			(roundrect_rratio 0.25)
			(net 3 "GND")
			(pintype "passive")
		)
	)
)
